(kicad_pcb
	(version 20260206)
	(generator "pcbnew")
	(generator_version "10.0")
	(general
		(thickness 1.6)
		(legacy_teardrops no)
	)
	(paper "A4")
	(title_block
		(title "01162023_DA0F0TEBIF0_F0T_Expander_BD_F_brd_V02_OCP.brd")
		(comment 1 "Grand Teton / footprints 1949-1955 of 9728")
	)
	(layers
		(0 "F.Cu" signal "TOP")
		(4 "In1.Cu" signal "GND")
		(6 "In2.Cu" signal "VCC")
		(8 "In3.Cu" signal "VCC1")
		(10 "In4.Cu" signal "GND1")
		(12 "In5.Cu" signal "IN1")
		(14 "In6.Cu" signal "GND2")
		(16 "In7.Cu" signal "IN2")
		(18 "In8.Cu" signal "GND3")
		(20 "In9.Cu" signal "IN3")
		(22 "In10.Cu" signal "GND4")
		(24 "In11.Cu" signal "IN4")
		(26 "In12.Cu" signal "GND5")
		(28 "In13.Cu" signal "IN5")
		(30 "In14.Cu" signal "GND6")
		(32 "In15.Cu" signal "IN6")
		(34 "In16.Cu" signal "GND7")
		(2 "B.Cu" signal "BOTTOM")
		(9 "F.Adhes" user "F.Adhesive")
		(11 "B.Adhes" user "B.Adhesive")
		(13 "F.Paste" user "Package Geometry/Pastemask Top")
		(15 "B.Paste" user "Package Geometry/Pastemask Bottom")
		(5 "F.SilkS" user "Ref Des/Silkscreen Top")
		(7 "B.SilkS" user "Ref Des/Silkscreen Bottom")
		(1 "F.Mask" user "Board Geometry/Soldermask Top")
		(3 "B.Mask" user "Board Geometry/Soldermask Bottom")
		(17 "Dwgs.User" user "User.Drawings")
		(19 "Cmts.User" user "User.Comments")
		(21 "Eco1.User" user "User.Eco1")
		(23 "Eco2.User" user "User.Eco2")
		(25 "Edge.Cuts" user "Board Geometry/Outline")
		(27 "Margin" user)
		(31 "F.CrtYd" user "Package Geometry/Place Bound Top")
		(29 "B.CrtYd" user "Package Geometry/Place Bound Bottom")
		(35 "F.Fab" user "Ref Des/Assembly Top")
		(33 "B.Fab" user "Ref Des/Assembly Bottom")
	)
	(footprint ""
		(layer "F.Cu")
		(at 239.416844 -377.863608 -90)
		(property "Reference" "PR6001"
			(at 0.399288 2.541778 90)
			(unlocked yes)
			(layer "F.SilkS")
			(effects
				(font
					(size 0.7874 0.5842)
					(thickness 0.1524)
				)
				(justify left)
			)
		)
		(property "Value" ""
			(at 0 0 270)
			(layer "F.Fab")
			(effects
				(font
					(size 1.27 1.27)
				)
			)
		)
		(duplicate_pad_numbers_are_jumpers no)
		(fp_line
			(start -4.0386 1.7526)
			(end -4.0386 -1.7526)
			(stroke
				(width 0.1524)
				(type default)
			)
			(layer "F.SilkS")
		)
		(fp_line
			(start 4.0386 1.7526)
			(end -4.0386 1.7526)
			(stroke
				(width 0.1524)
				(type default)
			)
			(layer "F.SilkS")
		)
		(fp_line
			(start -4.0386 -1.7526)
			(end 4.0386 -1.7526)
			(stroke
				(width 0.1524)
				(type default)
			)
			(layer "F.SilkS")
		)
		(fp_line
			(start 4.0386 -1.7526)
			(end 4.0386 1.7526)
			(stroke
				(width 0.1524)
				(type default)
			)
			(layer "F.SilkS")
		)
		(fp_line
			(start -4.0386 1.7526)
			(end -4.0386 -1.7526)
			(stroke
				(width 0.1)
				(type default)
			)
			(layer "F.Fab")
		)
		(fp_line
			(start 4.0386 1.7526)
			(end -4.0386 1.7526)
			(stroke
				(width 0.1)
				(type default)
			)
			(layer "F.Fab")
		)
		(fp_line
			(start -4.0386 -1.7526)
			(end 4.0386 -1.7526)
			(stroke
				(width 0.1)
				(type default)
			)
			(layer "F.Fab")
		)
		(fp_line
			(start 4.0386 -1.7526)
			(end 4.0386 1.7526)
			(stroke
				(width 0.1)
				(type default)
			)
			(layer "F.Fab")
		)
		(pad "1" smd circle
			(at -3.700018 0 180)
			(size 0 0)
			(layers "F.Cu" "F.Mask" "F.Paste")
			(net "P12V_STBY")
		)
		(pad "2" smd circle
			(at 3.700018 0)
			(size 0 0)
			(layers "F.Cu" "F.Mask" "F.Paste")
			(net "P12V_STBY_R1")
		)
		(pad "3" smd rect
			(at -2.70002 0)
			(size 0.4064 1.1176)
			(layers "F.Cu" "F.Mask" "F.Paste")
			(net "P12V_HSC_SENSE1_P")
		)
		(pad "4" smd rect
			(at 2.70002 0)
			(size 0.4064 1.1176)
			(layers "F.Cu" "F.Mask" "F.Paste")
			(net "P12V_HSC_SENSE1_N")
		)
	)
	(footprint ""
		(layer "F.Cu")
		(at 406.41905 -59.574684 90)
		(property "Reference" "PC588"
			(at 0 0 90)
			(layer "F.SilkS")
			(hide yes)
			(effects
				(font
					(size 1.27 1.27)
				)
			)
		)
		(property "Value" ""
			(at 0 0 90)
			(layer "F.Fab")
			(effects
				(font
					(size 1.27 1.27)
				)
			)
		)
		(duplicate_pad_numbers_are_jumpers no)
		(fp_line
			(start 0.7874 -0.4064)
			(end 0.7874 0.4064)
			(stroke
				(width 0.1524)
				(type default)
			)
			(layer "F.SilkS")
		)
		(fp_line
			(start -0.7874 -0.4064)
			(end 0.7874 -0.4064)
			(stroke
				(width 0.1524)
				(type default)
			)
			(layer "F.SilkS")
		)
		(fp_line
			(start 0.7874 0.4064)
			(end -0.7874 0.4064)
			(stroke
				(width 0.1524)
				(type default)
			)
			(layer "F.SilkS")
		)
		(fp_line
			(start -0.7874 0.4064)
			(end -0.7874 -0.4064)
			(stroke
				(width 0.1524)
				(type default)
			)
			(layer "F.SilkS")
		)
		(fp_line
			(start -0.12065 -0.305054)
			(end -0.12065 -0.2794)
			(stroke
				(width 0.1)
				(type default)
			)
			(layer "F.Fab")
		)
		(fp_line
			(start -0.67945 -0.305054)
			(end -0.12065 -0.305054)
			(stroke
				(width 0.1)
				(type default)
			)
			(layer "F.Fab")
		)
		(fp_line
			(start 0.67945 -0.3048)
			(end 0.67945 0.3048)
			(stroke
				(width 0.1)
				(type default)
			)
			(layer "F.Fab")
		)
		(fp_line
			(start 0.12065 -0.3048)
			(end 0.67945 -0.3048)
			(stroke
				(width 0.1)
				(type default)
			)
			(layer "F.Fab")
		)
		(fp_line
			(start 0.12065 -0.2794)
			(end 0.12065 -0.3048)
			(stroke
				(width 0.1)
				(type default)
			)
			(layer "F.Fab")
		)
		(fp_line
			(start -0.12065 -0.2794)
			(end 0.12065 -0.2794)
			(stroke
				(width 0.1)
				(type default)
			)
			(layer "F.Fab")
		)
		(fp_line
			(start 0.120396 0.2794)
			(end -0.12065 0.2794)
			(stroke
				(width 0.1)
				(type default)
			)
			(layer "F.Fab")
		)
		(fp_line
			(start -0.12065 0.2794)
			(end -0.12065 0.3048)
			(stroke
				(width 0.1)
				(type default)
			)
			(layer "F.Fab")
		)
		(fp_line
			(start 0.67945 0.3048)
			(end 0.120396 0.3048)
			(stroke
				(width 0.1)
				(type default)
			)
			(layer "F.Fab")
		)
		(fp_line
			(start 0.120396 0.3048)
			(end 0.120396 0.2794)
			(stroke
				(width 0.1)
				(type default)
			)
			(layer "F.Fab")
		)
		(fp_line
			(start -0.12065 0.3048)
			(end -0.67945 0.3048)
			(stroke
				(width 0.1)
				(type default)
			)
			(layer "F.Fab")
		)
		(fp_line
			(start -0.67945 0.3048)
			(end -0.67945 -0.305054)
			(stroke
				(width 0.1)
				(type default)
			)
			(layer "F.Fab")
		)
		(pad "1" smd circle
			(at -0.40005 0 90)
			(size 0 0)
			(layers "F.Cu" "F.Mask" "F.Paste")
			(net "P5V_AUX")
		)
		(pad "2" smd circle
			(at 0.40005 0 90)
			(size 0 0)
			(layers "F.Cu" "F.Mask" "F.Paste")
			(net "GND")
		)
	)
	(footprint ""
		(layer "F.Cu")
		(at 210.439 -206.375 180)
		(property "Reference" "R1512"
			(at 0 0 180)
			(layer "F.SilkS")
			(hide yes)
			(effects
				(font
					(size 1.27 1.27)
				)
			)
		)
		(property "Value" ""
			(at 0 0 180)
			(layer "F.Fab")
			(effects
				(font
					(size 1.27 1.27)
				)
			)
		)
		(duplicate_pad_numbers_are_jumpers no)
		(fp_line
			(start 0.7874 0.4064)
			(end -0.7874 0.4064)
			(stroke
				(width 0.1524)
				(type default)
			)
			(layer "F.SilkS")
		)
		(fp_line
			(start 0.7874 -0.4064)
			(end 0.7874 0.4064)
			(stroke
				(width 0.1524)
				(type default)
			)
			(layer "F.SilkS")
		)
		(fp_line
			(start -0.7874 0.4064)
			(end -0.7874 -0.4064)
			(stroke
				(width 0.1524)
				(type default)
			)
			(layer "F.SilkS")
		)
		(fp_line
			(start -0.7874 -0.4064)
			(end 0.7874 -0.4064)
			(stroke
				(width 0.1524)
				(type default)
			)
			(layer "F.SilkS")
		)
		(fp_line
			(start 0.67945 0.3048)
			(end 0.120396 0.3048)
			(stroke
				(width 0.1)
				(type default)
			)
			(layer "F.Fab")
		)
		(fp_line
			(start 0.67945 -0.3048)
			(end 0.67945 0.3048)
			(stroke
				(width 0.1)
				(type default)
			)
			(layer "F.Fab")
		)
		(fp_line
			(start 0.12065 -0.2794)
			(end 0.12065 -0.3048)
			(stroke
				(width 0.1)
				(type default)
			)
			(layer "F.Fab")
		)
		(fp_line
			(start 0.12065 -0.3048)
			(end 0.67945 -0.3048)
			(stroke
				(width 0.1)
				(type default)
			)
			(layer "F.Fab")
		)
		(fp_line
			(start 0.120396 0.3048)
			(end 0.120396 0.2794)
			(stroke
				(width 0.1)
				(type default)
			)
			(layer "F.Fab")
		)
		(fp_line
			(start 0.120396 0.2794)
			(end -0.12065 0.2794)
			(stroke
				(width 0.1)
				(type default)
			)
			(layer "F.Fab")
		)
		(fp_line
			(start -0.12065 0.3048)
			(end -0.67945 0.3048)
			(stroke
				(width 0.1)
				(type default)
			)
			(layer "F.Fab")
		)
		(fp_line
			(start -0.12065 0.2794)
			(end -0.12065 0.3048)
			(stroke
				(width 0.1)
				(type default)
			)
			(layer "F.Fab")
		)
		(fp_line
			(start -0.12065 -0.2794)
			(end 0.12065 -0.2794)
			(stroke
				(width 0.1)
				(type default)
			)
			(layer "F.Fab")
		)
		(fp_line
			(start -0.12065 -0.305054)
			(end -0.12065 -0.2794)
			(stroke
				(width 0.1)
				(type default)
			)
			(layer "F.Fab")
		)
		(fp_line
			(start -0.67945 0.3048)
			(end -0.67945 -0.305054)
			(stroke
				(width 0.1)
				(type default)
			)
			(layer "F.Fab")
		)
		(fp_line
			(start -0.67945 -0.305054)
			(end -0.12065 -0.305054)
			(stroke
				(width 0.1)
				(type default)
			)
			(layer "F.Fab")
		)
		(pad "1" smd circle
			(at -0.40005 0 180)
			(size 0 0)
			(layers "F.Cu" "F.Mask" "F.Paste")
			(net "SMB_NIC4_R_SCL")
		)
		(pad "2" smd circle
			(at 0.40005 0 180)
			(size 0 0)
			(layers "F.Cu" "F.Mask" "F.Paste")
			(net "P1V2_AUX")
		)
	)
	(footprint ""
		(layer "F.Cu")
		(at 314.861448 -148.91131 180)
		(property "Reference" "C431"
			(at 0 0 180)
			(layer "F.SilkS")
			(hide yes)
			(effects
				(font
					(size 1.27 1.27)
				)
			)
		)
		(property "Value" ""
			(at 0 0 180)
			(layer "F.Fab")
			(effects
				(font
					(size 1.27 1.27)
				)
			)
		)
		(duplicate_pad_numbers_are_jumpers no)
		(fp_line
			(start 0.299974 0.150114)
			(end -0.299974 0.150114)
			(stroke
				(width 0.1)
				(type default)
			)
			(layer "F.Fab")
		)
		(fp_line
			(start 0.299974 -0.150114)
			(end 0.299974 0.150114)
			(stroke
				(width 0.1)
				(type default)
			)
			(layer "F.Fab")
		)
		(fp_line
			(start -0.299974 0.150114)
			(end -0.299974 -0.150114)
			(stroke
				(width 0.1)
				(type default)
			)
			(layer "F.Fab")
		)
		(fp_line
			(start -0.299974 -0.150114)
			(end 0.299974 -0.150114)
			(stroke
				(width 0.1)
				(type default)
			)
			(layer "F.Fab")
		)
		(pad "1" smd rect
			(at -0.2667 0 180)
			(size 0.3048 0.381)
			(layers "F.Cu" "F.Mask" "F.Paste")
			(net "P5E_PEX2_STN0_TX_DP<11>")
		)
		(pad "2" smd rect
			(at 0.2667 0 180)
			(size 0.3048 0.381)
			(layers "F.Cu" "F.Mask" "F.Paste")
			(net "P5E_PEX2_STN0_TX_C_DP<11>")
		)
	)
	(footprint ""
		(layer "F.Cu")
		(at 184.491884 -194.090798 180)
		(property "Reference" "R471"
			(at 0 0 180)
			(layer "F.SilkS")
			(hide yes)
			(effects
				(font
					(size 1.27 1.27)
				)
			)
		)
		(property "Value" ""
			(at 0 0 180)
			(layer "F.Fab")
			(effects
				(font
					(size 1.27 1.27)
				)
			)
		)
		(duplicate_pad_numbers_are_jumpers no)
		(fp_line
			(start 0.7874 0.4064)
			(end -0.7874 0.4064)
			(stroke
				(width 0.1524)
				(type default)
			)
			(layer "F.SilkS")
		)
		(fp_line
			(start 0.7874 -0.4064)
			(end 0.7874 0.4064)
			(stroke
				(width 0.1524)
				(type default)
			)
			(layer "F.SilkS")
		)
		(fp_line
			(start -0.7874 0.4064)
			(end -0.7874 -0.4064)
			(stroke
				(width 0.1524)
				(type default)
			)
			(layer "F.SilkS")
		)
		(fp_line
			(start -0.7874 -0.4064)
			(end 0.7874 -0.4064)
			(stroke
				(width 0.1524)
				(type default)
			)
			(layer "F.SilkS")
		)
		(fp_line
			(start 0.67945 0.3048)
			(end 0.120396 0.3048)
			(stroke
				(width 0.1)
				(type default)
			)
			(layer "F.Fab")
		)
		(fp_line
			(start 0.67945 -0.3048)
			(end 0.67945 0.3048)
			(stroke
				(width 0.1)
				(type default)
			)
			(layer "F.Fab")
		)
		(fp_line
			(start 0.12065 -0.2794)
			(end 0.12065 -0.3048)
			(stroke
				(width 0.1)
				(type default)
			)
			(layer "F.Fab")
		)
		(fp_line
			(start 0.12065 -0.3048)
			(end 0.67945 -0.3048)
			(stroke
				(width 0.1)
				(type default)
			)
			(layer "F.Fab")
		)
		(fp_line
			(start 0.120396 0.3048)
			(end 0.120396 0.2794)
			(stroke
				(width 0.1)
				(type default)
			)
			(layer "F.Fab")
		)
		(fp_line
			(start 0.120396 0.2794)
			(end -0.12065 0.2794)
			(stroke
				(width 0.1)
				(type default)
			)
			(layer "F.Fab")
		)
		(fp_line
			(start -0.12065 0.3048)
			(end -0.67945 0.3048)
			(stroke
				(width 0.1)
				(type default)
			)
			(layer "F.Fab")
		)
		(fp_line
			(start -0.12065 0.2794)
			(end -0.12065 0.3048)
			(stroke
				(width 0.1)
				(type default)
			)
			(layer "F.Fab")
		)
		(fp_line
			(start -0.12065 -0.2794)
			(end 0.12065 -0.2794)
			(stroke
				(width 0.1)
				(type default)
			)
			(layer "F.Fab")
		)
		(fp_line
			(start -0.12065 -0.305054)
			(end -0.12065 -0.2794)
			(stroke
				(width 0.1)
				(type default)
			)
			(layer "F.Fab")
		)
		(fp_line
			(start -0.67945 0.3048)
			(end -0.67945 -0.305054)
			(stroke
				(width 0.1)
				(type default)
			)
			(layer "F.Fab")
		)
		(fp_line
			(start -0.67945 -0.305054)
			(end -0.12065 -0.305054)
			(stroke
				(width 0.1)
				(type default)
			)
			(layer "F.Fab")
		)
		(pad "1" smd circle
			(at -0.40005 0 180)
			(size 0 0)
			(layers "F.Cu" "F.Mask" "F.Paste")
			(net "SPI_BIC1_MOSI_R2")
		)
		(pad "2" smd circle
			(at 0.40005 0 180)
			(size 0 0)
			(layers "F.Cu" "F.Mask" "F.Paste")
			(net "SPI_BIC1_MOSI_R3")
		)
	)
	(footprint ""
		(layer "F.Cu")
		(at 125.16739 -262.17372 180)
		(property "Reference" "PR77"
			(at 0 0 180)
			(layer "F.SilkS")
			(hide yes)
			(effects
				(font
					(size 1.27 1.27)
				)
			)
		)
		(property "Value" ""
			(at 0 0 180)
			(layer "F.Fab")
			(effects
				(font
					(size 1.27 1.27)
				)
			)
		)
		(duplicate_pad_numbers_are_jumpers no)
		(fp_line
			(start 0.7874 0.4064)
			(end -0.7874 0.4064)
			(stroke
				(width 0.1524)
				(type default)
			)
			(layer "F.SilkS")
		)
		(fp_line
			(start 0.7874 -0.4064)
			(end 0.7874 0.4064)
			(stroke
				(width 0.1524)
				(type default)
			)
			(layer "F.SilkS")
		)
		(fp_line
			(start -0.7874 0.4064)
			(end -0.7874 -0.4064)
			(stroke
				(width 0.1524)
				(type default)
			)
			(layer "F.SilkS")
		)
		(fp_line
			(start -0.7874 -0.4064)
			(end 0.7874 -0.4064)
			(stroke
				(width 0.1524)
				(type default)
			)
			(layer "F.SilkS")
		)
		(fp_line
			(start 0.67945 0.3048)
			(end 0.120396 0.3048)
			(stroke
				(width 0.1)
				(type default)
			)
			(layer "F.Fab")
		)
		(fp_line
			(start 0.67945 -0.3048)
			(end 0.67945 0.3048)
			(stroke
				(width 0.1)
				(type default)
			)
			(layer "F.Fab")
		)
		(fp_line
			(start 0.12065 -0.2794)
			(end 0.12065 -0.3048)
			(stroke
				(width 0.1)
				(type default)
			)
			(layer "F.Fab")
		)
		(fp_line
			(start 0.12065 -0.3048)
			(end 0.67945 -0.3048)
			(stroke
				(width 0.1)
				(type default)
			)
			(layer "F.Fab")
		)
		(fp_line
			(start 0.120396 0.3048)
			(end 0.120396 0.2794)
			(stroke
				(width 0.1)
				(type default)
			)
			(layer "F.Fab")
		)
		(fp_line
			(start 0.120396 0.2794)
			(end -0.12065 0.2794)
			(stroke
				(width 0.1)
				(type default)
			)
			(layer "F.Fab")
		)
		(fp_line
			(start -0.12065 0.3048)
			(end -0.67945 0.3048)
			(stroke
				(width 0.1)
				(type default)
			)
			(layer "F.Fab")
		)
		(fp_line
			(start -0.12065 0.2794)
			(end -0.12065 0.3048)
			(stroke
				(width 0.1)
				(type default)
			)
			(layer "F.Fab")
		)
		(fp_line
			(start -0.12065 -0.2794)
			(end 0.12065 -0.2794)
			(stroke
				(width 0.1)
				(type default)
			)
			(layer "F.Fab")
		)
		(fp_line
			(start -0.12065 -0.305054)
			(end -0.12065 -0.2794)
			(stroke
				(width 0.1)
				(type default)
			)
			(layer "F.Fab")
		)
		(fp_line
			(start -0.67945 0.3048)
			(end -0.67945 -0.305054)
			(stroke
				(width 0.1)
				(type default)
			)
			(layer "F.Fab")
		)
		(fp_line
			(start -0.67945 -0.305054)
			(end -0.12065 -0.305054)
			(stroke
				(width 0.1)
				(type default)
			)
			(layer "F.Fab")
		)
		(pad "1" smd circle
			(at -0.40005 0 180)
			(size 0 0)
			(layers "F.Cu" "F.Mask" "F.Paste")
			(net "SH_P0V8_PEX0_VSEN0_R")
		)
		(pad "2" smd circle
			(at 0.40005 0 180)
			(size 0 0)
			(layers "F.Cu" "F.Mask" "F.Paste")
			(net "P0V8_PEX0_VSEN0")
		)
	)
	(footprint ""
		(layer "F.Cu")
		(at 196.119242 -149.79015 180)
		(property "Reference" "C219"
			(at 0 0 180)
			(layer "F.SilkS")
			(hide yes)
			(effects
				(font
					(size 1.27 1.27)
				)
			)
		)
		(property "Value" ""
			(at 0 0 180)
			(layer "F.Fab")
			(effects
				(font
					(size 1.27 1.27)
				)
			)
		)
		(duplicate_pad_numbers_are_jumpers no)
		(fp_line
			(start 0.299974 0.150114)
			(end -0.299974 0.150114)
			(stroke
				(width 0.1)
				(type default)
			)
			(layer "F.Fab")
		)
		(fp_line
			(start 0.299974 -0.150114)
			(end 0.299974 0.150114)
			(stroke
				(width 0.1)
				(type default)
			)
			(layer "F.Fab")
		)
		(fp_line
			(start -0.299974 0.150114)
			(end -0.299974 -0.150114)
			(stroke
				(width 0.1)
				(type default)
			)
			(layer "F.Fab")
		)
		(fp_line
			(start -0.299974 -0.150114)
			(end 0.299974 -0.150114)
			(stroke
				(width 0.1)
				(type default)
			)
			(layer "F.Fab")
		)
		(pad "1" smd rect
			(at -0.2667 0 180)
			(size 0.3048 0.381)
			(layers "F.Cu" "F.Mask" "F.Paste")
			(net "P5E_PEX1_STN0_TX_DP<12>")
		)
		(pad "2" smd rect
			(at 0.2667 0 180)
			(size 0.3048 0.381)
			(layers "F.Cu" "F.Mask" "F.Paste")
			(net "P5E_PEX1_STN0_TX_C_DP<12>")
		)
	)
)
